(kicad_pcb
	(version 20241229)
	(generator "pcbnew")
	(generator_version "9.0")
	(general
		(thickness 1.63)
		(legacy_teardrops no)
	)
	(paper "A4")
	(title_block
		(title "CM4 Baseboard")
		(date "2026-01-05")
		(rev "1.1.1")
		(company "Antmicro Ltd")
		(comment 1 "www.antmicro.com")
		(comment 9 "footprints 198-199 of 506")
	)
	(layers
		(0 "F.Cu" signal)
		(4 "In1.Cu" power)
		(6 "In2.Cu" power)
		(8 "In3.Cu" signal)
		(10 "In4.Cu" signal)
		(2 "B.Cu" signal)
		(9 "F.Adhes" user "F.Adhesive")
		(11 "B.Adhes" user "B.Adhesive")
		(13 "F.Paste" user)
		(15 "B.Paste" user)
		(5 "F.SilkS" user "F.Silkscreen")
		(7 "B.SilkS" user "B.Silkscreen")
		(1 "F.Mask" user)
		(3 "B.Mask" user)
		(17 "Dwgs.User" user "User.Drawings")
		(19 "Cmts.User" user "User.Comments")
		(21 "Eco1.User" user "User.Eco1")
		(23 "Eco2.User" user "User.Eco2")
		(25 "Edge.Cuts" user)
		(27 "Margin" user)
		(31 "F.CrtYd" user "F.Courtyard")
		(29 "B.CrtYd" user "B.Courtyard")
		(35 "F.Fab" user)
		(33 "B.Fab" user)
	)
	(footprint "antmicro-footprints:Nexperia_DFN-10_2.5x1mm_P0.5mm"
		(layer "F.Cu")
		(at 142.292962 150.3415 90)
		(property "Reference" "D801"
			(at -5.575 1.225 90)
			(layer "F.SilkS")
			(effects
				(font
					(size 0.7 0.7)
					(thickness 0.15)
				)
				(justify left bottom)
			)
		)
		(property "Value" "PUSB3F96X_PASS"
			(at -0.016 1.705 90)
			(layer "F.Fab")
			(effects
				(font
					(size 0.7 0.7)
					(thickness 0.15)
				)
				(justify left bottom)
			)
		)
		(property "Datasheet" "https://mouser.com/datasheet/2/916/PUSB3F96-1600324.pdf"
			(at 0 0 90)
			(layer "F.Fab")
			(hide yes)
			(effects
				(font
					(size 1.27 1.27)
					(thickness 0.15)
				)
			)
		)
		(property "Manufacturer" "Nexperia"
			(at 0 0 90)
			(unlocked yes)
			(layer "F.Fab")
			(hide yes)
			(effects
				(font
					(size 1 1)
					(thickness 0.15)
				)
			)
		)
		(property "MPN" "PUSB3F96X"
			(at 0 0 90)
			(unlocked yes)
			(layer "F.Fab")
			(hide yes)
			(effects
				(font
					(size 1 1)
					(thickness 0.15)
				)
			)
		)
		(property "Author" "Antmicro"
			(at 0 0 90)
			(unlocked yes)
			(layer "F.Fab")
			(hide yes)
			(effects
				(font
					(size 1 1)
					(thickness 0.15)
				)
			)
		)
		(property "License" "Apache-2.0"
			(at 0 0 90)
			(unlocked yes)
			(layer "F.Fab")
			(hide yes)
			(effects
				(font
					(size 1 1)
					(thickness 0.15)
				)
			)
		)
		(sheetname "/Peripherals/")
		(sheetfile "peripherals.kicad_sch")
		(attr smd)
		(fp_line
			(start -1.375 -0.4)
			(end -1.375 0.4)
			(stroke
				(width 0.15)
				(type solid)
			)
			(layer "F.SilkS")
		)
		(fp_line
			(start 1.375 0.4)
			(end 1.375 -0.4)
			(stroke
				(width 0.15)
				(type solid)
			)
			(layer "F.SilkS")
		)
		(fp_circle
			(center -1.4 0.7)
			(end -1.349 0.7)
			(stroke
				(width 0.15)
				(type solid)
			)
			(fill yes)
			(layer "F.SilkS")
		)
		(fp_rect
			(start -1.4 -0.725)
			(end 1.4 0.725)
			(stroke
				(width 0.05)
				(type solid)
			)
			(fill no)
			(layer "F.CrtYd")
		)
		(fp_line
			(start 1.25 -0.5)
			(end -1.25 -0.5)
			(stroke
				(width 0.15)
				(type solid)
			)
			(layer "F.Fab")
		)
		(fp_line
			(start -1.25 -0.5)
			(end -1.25 0.15)
			(stroke
				(width 0.15)
				(type solid)
			)
			(layer "F.Fab")
		)
		(fp_line
			(start -1.25 0.15)
			(end -0.9 0.5)
			(stroke
				(width 0.15)
				(type solid)
			)
			(layer "F.Fab")
		)
		(fp_line
			(start 1.25 0.5)
			(end 1.25 -0.5)
			(stroke
				(width 0.15)
				(type solid)
			)
			(layer "F.Fab")
		)
		(fp_line
			(start -0.9 0.5)
			(end 1.25 0.5)
			(stroke
				(width 0.15)
				(type solid)
			)
			(layer "F.Fab")
		)
		(fp_text user "License: Apache-2.0"
			(at -1.367 6.105 90)
			(layer "F.Fab")
			(effects
				(font
					(size 0.7 0.7)
					(thickness 0.15)
				)
				(justify left bottom)
			)
		)
		(fp_text user "Author: Antmicro"
			(at -1.367 4.905 90)
			(layer "F.Fab")
			(effects
				(font
					(size 0.7 0.7)
					(thickness 0.15)
				)
				(justify left bottom)
			)
		)
		(fp_text user "${REFERENCE}"
			(at -1.367 3.704 90)
			(layer "F.Fab")
			(effects
				(font
					(size 0.7 0.7)
					(thickness 0.15)
				)
				(justify left bottom)
			)
		)
		(pad "1" smd rect
			(at -1 0.3875 90)
			(size 0.2 0.475)
			(layers "F.Cu" "F.Mask" "F.Paste")
			(net 9 "+3V3")
			(pinfunction "CH1")
			(pintype "passive")
			(solder_mask_margin 0.05)
		)
		(pad "2" smd rect
			(at -0.5 0.3875 90)
			(size 0.2 0.475)
			(layers "F.Cu" "F.Mask" "F.Paste")
			(net 243 "/Compute module/GPIO.2")
			(pinfunction "CH2")
			(pintype "passive")
			(solder_mask_margin 0.05)
		)
		(pad "3" smd rect
			(at 0 0.3875 90)
			(size 0.2 0.475)
			(layers "F.Cu" "F.Mask" "F.Paste")
			(net 3 "GND")
			(pinfunction "GND")
			(pintype "passive")
			(solder_mask_margin 0.05)
		)
		(pad "4" smd rect
			(at 0.5 0.3875 90)
			(size 0.2 0.475)
			(layers "F.Cu" "F.Mask" "F.Paste")
			(net 242 "/Compute module/GPIO.3")
			(pinfunction "CH3")
			(pintype "passive")
			(solder_mask_margin 0.05)
		)
		(pad "5" smd rect
			(at 1 0.3875 90)
			(size 0.2 0.475)
			(layers "F.Cu" "F.Mask" "F.Paste")
			(net 240 "/Compute module/GPIO.4{slash}TXD3")
			(pinfunction "CH4")
			(pintype "passive")
			(solder_mask_margin 0.05)
		)
		(pad "6" smd rect
			(at 1 -0.3875 90)
			(size 0.2 0.475)
			(layers "F.Cu" "F.Mask" "F.Paste")
			(net 240 "/Compute module/GPIO.4{slash}TXD3")
			(pinfunction "CH4")
			(pintype "passive")
			(solder_mask_margin 0.05)
		)
		(pad "7" smd rect
			(at 0.5 -0.3875 90)
			(size 0.2 0.475)
			(layers "F.Cu" "F.Mask" "F.Paste")
			(net 242 "/Compute module/GPIO.3")
			(pinfunction "CH3")
			(pintype "passive")
			(solder_mask_margin 0.05)
		)
		(pad "8" smd rect
			(at 0 -0.3875 90)
			(size 0.2 0.475)
			(layers "F.Cu" "F.Mask" "F.Paste")
			(net 3 "GND")
			(pinfunction "GND")
			(pintype "passive")
			(solder_mask_margin 0.05)
		)
		(pad "9" smd rect
			(at -0.501 -0.3875 90)
			(size 0.2 0.475)
			(layers "F.Cu" "F.Mask" "F.Paste")
			(net 243 "/Compute module/GPIO.2")
			(pinfunction "CH2")
			(pintype "passive")
			(solder_mask_margin 0.05)
		)
		(pad "10" smd rect
			(at -1 -0.3875 90)
			(size 0.2 0.475)
			(layers "F.Cu" "F.Mask" "F.Paste")
			(net 9 "+3V3")
			(pinfunction "CH1")
			(pintype "passive")
			(solder_mask_margin 0.05)
		)
	)
	(footprint "antmicro-footprints:Nexperia_DFN-10_2.5x1mm_P0.5mm"
		(layer "F.Cu")
		(at 122.987962 118.8965)
		(property "Reference" "D805"
			(at -2.99 2.18 0)
			(layer "F.SilkS")
			(effects
				(font
					(size 0.7 0.7)
					(thickness 0.15)
				)
				(justify left bottom)
			)
		)
		(property "Value" "PUSB3F96X_PASS"
			(at -0.016 1.705 0)
			(layer "F.Fab")
			(effects
				(font
					(size 0.7 0.7)
					(thickness 0.15)
				)
				(justify left bottom)
			)
		)
		(property "Datasheet" "https://mouser.com/datasheet/2/916/PUSB3F96-1600324.pdf"
			(at 0 0 0)
			(layer "F.Fab")
			(hide yes)
			(effects
				(font
					(size 1.27 1.27)
					(thickness 0.15)
				)
			)
		)
		(property "Manufacturer" "Nexperia"
			(at 0 0 0)
			(unlocked yes)
			(layer "F.Fab")
			(hide yes)
			(effects
				(font
					(size 1 1)
					(thickness 0.15)
				)
			)
		)
		(property "MPN" "PUSB3F96X"
			(at 0 0 0)
			(unlocked yes)
			(layer "F.Fab")
			(hide yes)
			(effects
				(font
					(size 1 1)
					(thickness 0.15)
				)
			)
		)
		(property "Author" "Antmicro"
			(at 0 0 0)
			(unlocked yes)
			(layer "F.Fab")
			(hide yes)
			(effects
				(font
					(size 1 1)
					(thickness 0.15)
				)
			)
		)
		(property "License" "Apache-2.0"
			(at 0 0 0)
			(unlocked yes)
			(layer "F.Fab")
			(hide yes)
			(effects
				(font
					(size 1 1)
					(thickness 0.15)
				)
			)
		)
		(sheetname "/Peripherals/")
		(sheetfile "peripherals.kicad_sch")
		(attr smd)
		(fp_line
			(start -1.375 -0.4)
			(end -1.375 0.4)
			(stroke
				(width 0.15)
				(type solid)
			)
			(layer "F.SilkS")
		)
		(fp_line
			(start 1.375 0.4)
			(end 1.375 -0.4)
			(stroke
				(width 0.15)
				(type solid)
			)
			(layer "F.SilkS")
		)
		(fp_circle
			(center -1.4 0.7)
			(end -1.349 0.7)
			(stroke
				(width 0.15)
				(type solid)
			)
			(fill yes)
			(layer "F.SilkS")
		)
		(fp_rect
			(start -1.4 -0.725)
			(end 1.4 0.725)
			(stroke
				(width 0.05)
				(type solid)
			)
			(fill no)
			(layer "F.CrtYd")
		)
		(fp_line
			(start -1.25 -0.5)
			(end -1.25 0.15)
			(stroke
				(width 0.15)
				(type solid)
			)
			(layer "F.Fab")
		)
		(fp_line
			(start -1.25 0.15)
			(end -0.9 0.5)
			(stroke
				(width 0.15)
				(type solid)
			)
			(layer "F.Fab")
		)
		(fp_line
			(start -0.9 0.5)
			(end 1.25 0.5)
			(stroke
				(width 0.15)
				(type solid)
			)
			(layer "F.Fab")
		)
		(fp_line
			(start 1.25 -0.5)
			(end -1.25 -0.5)
			(stroke
				(width 0.15)
				(type solid)
			)
			(layer "F.Fab")
		)
		(fp_line
			(start 1.25 0.5)
			(end 1.25 -0.5)
			(stroke
				(width 0.15)
				(type solid)
			)
			(layer "F.Fab")
		)
		(fp_text user "License: Apache-2.0"
			(at -1.367 6.105 0)
			(layer "F.Fab")
			(effects
				(font
					(size 0.7 0.7)
					(thickness 0.15)
				)
				(justify left bottom)
			)
		)
		(fp_text user "${REFERENCE}"
			(at -1.367 3.704 0)
			(layer "F.Fab")
			(effects
				(font
					(size 0.7 0.7)
					(thickness 0.15)
				)
				(justify left bottom)
			)
		)
		(fp_text user "Author: Antmicro"
			(at -1.367 4.905 0)
			(layer "F.Fab")
			(effects
				(font
					(size 0.7 0.7)
					(thickness 0.15)
				)
				(justify left bottom)
			)
		)
		(pad "1" smd rect
			(at -1 0.3875)
			(size 0.2 0.475)
			(layers "F.Cu" "F.Mask" "F.Paste")
			(net 142 "/CSI/I_{2}C1.SCL")
			(pinfunction "CH1")
			(pintype "passive")
			(solder_mask_margin 0.05)
		)
		(pad "2" smd rect
			(at -0.5 0.3875)
			(size 0.2 0.475)
			(layers "F.Cu" "F.Mask" "F.Paste")
			(net 143 "/CSI/I_{2}C1.SDA")
			(pinfunction "CH2")
			(pintype "passive")
			(solder_mask_margin 0.05)
		)
		(pad "3" smd rect
			(at 0 0.3875)
			(size 0.2 0.475)
			(layers "F.Cu" "F.Mask" "F.Paste")
			(net 3 "GND")
			(pinfunction "GND")
			(pintype "passive")
			(solder_mask_margin 0.05)
		)
		(pad "4" smd rect
			(at 0.5 0.3875)
			(size 0.2 0.475)
			(layers "F.Cu" "F.Mask" "F.Paste")
			(net 9 "+3V3")
			(pinfunction "CH3")
			(pintype "passive")
			(solder_mask_margin 0.05)
		)
		(pad "5" smd rect
			(at 1 0.3875)
			(size 0.2 0.475)
			(layers "F.Cu" "F.Mask" "F.Paste")
			(net 3 "GND")
			(pinfunction "CH4")
			(pintype "passive")
			(solder_mask_margin 0.05)
		)
		(pad "6" smd rect
			(at 1 -0.3875)
			(size 0.2 0.475)
			(layers "F.Cu" "F.Mask" "F.Paste")
			(net 3 "GND")
			(pinfunction "CH4")
			(pintype "passive")
			(solder_mask_margin 0.05)
		)
		(pad "7" smd rect
			(at 0.5 -0.3875)
			(size 0.2 0.475)
			(layers "F.Cu" "F.Mask" "F.Paste")
			(net 9 "+3V3")
			(pinfunction "CH3")
			(pintype "passive")
			(solder_mask_margin 0.05)
		)
		(pad "8" smd rect
			(at 0 -0.3875)
			(size 0.2 0.475)
			(layers "F.Cu" "F.Mask" "F.Paste")
			(net 3 "GND")
			(pinfunction "GND")
			(pintype "passive")
			(solder_mask_margin 0.05)
		)
		(pad "9" smd rect
			(at -0.501 -0.3875)
			(size 0.2 0.475)
			(layers "F.Cu" "F.Mask" "F.Paste")
			(net 143 "/CSI/I_{2}C1.SDA")
			(pinfunction "CH2")
			(pintype "passive")
			(solder_mask_margin 0.05)
		)
		(pad "10" smd rect
			(at -1 -0.3875)
			(size 0.2 0.475)
			(layers "F.Cu" "F.Mask" "F.Paste")
			(net 142 "/CSI/I_{2}C1.SCL")
			(pinfunction "CH1")
			(pintype "passive")
			(solder_mask_margin 0.05)
		)
	)
)
